# T6G (Grand Teton) — schematic netlist excerpt (pin names and nets, part order shuffled) for the footprints in the layout excerpt that follows; sources: Cadence DE-HDL packaged netlist, KiCad conversion of 04192023_DAF0TMB3IC0_F0TG_MB_C_brd_V02_OCP.brd

R81  Q_RES  33 5% CHIP  pkg 0402LF  page 82 : A = FM_INT_CPU0_HP_UBM_R_N ; B = FM_INT_CPU0_HP_UBM_N
PC158_6  Q_CAP  22UF 16V 20% X6S  pkg C0805  page 196 : A = SW_P12V_AUX_PVDDCR_CPU0_P0_FLT ; B = GND
R921  Q_RES  4.7K 5% CHIP  pkg 0201LF  page 353 : A = TEST1_RT_CPU1_P3 ; B = GND
C6754  Q_CAP_DIFFBUS  DIFF BUS_0.22UF 6.3V 20% X6S  pkg C0201  page 352 : \1\ = P5E_CPU1_P3_TX_BUF_C_DN<14> ; \2\ = P5E_CPU1_P3_TX_BUF_DN<14>

(kicad_pcb
	(version 20260206)
	(generator "pcbnew")
	(generator_version "10.0")
	(general
		(thickness 1.6)
		(legacy_teardrops no)
	)
	(paper "A4")
	(title_block
		(title "04192023_DAF0TMB3IC0_F0TG_MB_C_brd_V02_OCP.brd")
		(comment 1 "Grand Teton / footprints 6809-6812 of 8354")
	)
	(layers
		(0 "F.Cu" signal "TOP")
		(4 "In1.Cu" signal "GND")
		(6 "In2.Cu" signal "IN1")
		(8 "In3.Cu" signal "GND1")
		(10 "In4.Cu" signal "IN2")
		(12 "In5.Cu" signal "GND2")
		(14 "In6.Cu" signal "IN3")
		(16 "In7.Cu" signal "GND3")
		(18 "In8.Cu" signal "VCC")
		(20 "In9.Cu" signal "VCC1")
		(22 "In10.Cu" signal "GND4")
		(24 "In11.Cu" signal "IN4")
		(26 "In12.Cu" signal "GND5")
		(28 "In13.Cu" signal "IN5")
		(30 "In14.Cu" signal "GND6")
		(32 "In15.Cu" signal "IN6")
		(34 "In16.Cu" signal "GND7")
		(2 "B.Cu" signal "BOTTOM")
		(9 "F.Adhes" user "F.Adhesive")
		(11 "B.Adhes" user "B.Adhesive")
		(13 "F.Paste" user "Package Geometry/Pastemask Top")
		(15 "B.Paste" user "Package Geometry/Pastemask Bottom")
		(5 "F.SilkS" user "Ref Des/Silkscreen Top")
		(7 "B.SilkS" user "Ref Des/Silkscreen Bottom")
		(1 "F.Mask" user "Board Geometry/Soldermask Top")
		(3 "B.Mask" user "Board Geometry/Soldermask Bottom")
		(17 "Dwgs.User" user "User.Drawings")
		(19 "Cmts.User" user "User.Comments")
		(21 "Eco1.User" user "User.Eco1")
		(23 "Eco2.User" user "User.Eco2")
		(25 "Edge.Cuts" user "Board Geometry/Outline")
		(27 "Margin" user)
		(31 "F.CrtYd" user "Package Geometry/Place Bound Top")
		(29 "B.CrtYd" user "Package Geometry/Place Bound Bottom")
		(35 "F.Fab" user "Ref Des/Assembly Top")
		(33 "B.Fab" user "Ref Des/Assembly Bottom")
	)
	(footprint ""
		(layer "B.Cu")
		(at 346.700856 -161.263076 -90)
		(property "Reference" "PC158_6"
			(at 0 0 90)
			(layer "B.SilkS")
			(hide yes)
			(effects
				(font
					(size 1.27 1.27)
				)
				(justify mirror)
			)
		)
		(property "Value" ""
			(at 0 0 90)
			(layer "B.Fab")
			(effects
				(font
					(size 1.27 1.27)
				)
				(justify mirror)
			)
		)
		(duplicate_pad_numbers_are_jumpers no)
		(fp_line
			(start -1.524 0.762)
			(end 1.524 0.762)
			(stroke
				(width 0.1524)
				(type default)
			)
			(layer "B.SilkS")
		)
		(fp_line
			(start 1.524 0.762)
			(end 1.524 -0.762)
			(stroke
				(width 0.1524)
				(type default)
			)
			(layer "B.SilkS")
		)
		(fp_line
			(start -1.524 -0.762)
			(end -1.524 0.762)
			(stroke
				(width 0.1524)
				(type default)
			)
			(layer "B.SilkS")
		)
		(fp_line
			(start 1.524 -0.762)
			(end -1.524 -0.762)
			(stroke
				(width 0.1524)
				(type default)
			)
			(layer "B.SilkS")
		)
		(fp_line
			(start -1.1049 0.724916)
			(end -1.1049 -0.724916)
			(stroke
				(width 0.1)
				(type default)
			)
			(layer "B.Fab")
		)
		(fp_line
			(start 1.1049 0.724916)
			(end -1.1049 0.724916)
			(stroke
				(width 0.1)
				(type default)
			)
			(layer "B.Fab")
		)
		(fp_line
			(start -1.1049 -0.724916)
			(end 1.1049 -0.724916)
			(stroke
				(width 0.1)
				(type default)
			)
			(layer "B.Fab")
		)
		(fp_line
			(start 1.1049 -0.724916)
			(end 1.1049 0.724916)
			(stroke
				(width 0.1)
				(type default)
			)
			(layer "B.Fab")
		)
		(pad "1" smd rect
			(at 0.889 0 270)
			(size 1.016 1.27)
			(layers "B.Cu" "B.Mask" "B.Paste")
			(net "SW_P12V_AUX_PVDDCR_CPU0_P0_FLT")
		)
		(pad "2" smd rect
			(at -0.889 0 270)
			(size 1.016 1.27)
			(layers "B.Cu" "B.Mask" "B.Paste")
			(net "GND")
		)
	)
	(footprint ""
		(layer "B.Cu")
		(at 110.365794 -384.66268 180)
		(property "Reference" "R921"
			(at 0 0 0)
			(layer "B.SilkS")
			(hide yes)
			(effects
				(font
					(size 1.27 1.27)
				)
				(justify mirror)
			)
		)
		(property "Value" ""
			(at 0 0 0)
			(layer "B.Fab")
			(effects
				(font
					(size 1.27 1.27)
				)
				(justify mirror)
			)
		)
		(duplicate_pad_numbers_are_jumpers no)
		(fp_line
			(start 0.32512 0.175006)
			(end 0.32512 -0.175006)
			(stroke
				(width 0.1)
				(type default)
			)
			(layer "B.Fab")
		)
		(fp_line
			(start 0.32512 -0.175006)
			(end -0.32512 -0.175006)
			(stroke
				(width 0.1)
				(type default)
			)
			(layer "B.Fab")
		)
		(fp_line
			(start -0.32512 0.175006)
			(end 0.32512 0.175006)
			(stroke
				(width 0.1)
				(type default)
			)
			(layer "B.Fab")
		)
		(fp_line
			(start -0.32512 -0.175006)
			(end -0.32512 0.175006)
			(stroke
				(width 0.1)
				(type default)
			)
			(layer "B.Fab")
		)
		(pad "1" smd rect
			(at 0.2667 0)
			(size 0.3048 0.381)
			(layers "B.Cu" "B.Mask" "B.Paste")
			(net "TEST1_RT_CPU1_P3")
		)
		(pad "2" smd rect
			(at -0.2667 0 180)
			(size 0.3048 0.381)
			(layers "B.Cu" "B.Mask" "B.Paste")
			(net "GND")
		)
	)
	(footprint ""
		(layer "B.Cu")
		(at 182.753 -100.294948 90)
		(property "Reference" "R81"
			(at 0 0 90)
			(layer "B.SilkS")
			(hide yes)
			(effects
				(font
					(size 1.27 1.27)
				)
				(justify mirror)
			)
		)
		(property "Value" ""
			(at 0 0 90)
			(layer "B.Fab")
			(effects
				(font
					(size 1.27 1.27)
				)
				(justify mirror)
			)
		)
		(duplicate_pad_numbers_are_jumpers no)
		(fp_line
			(start 0.7874 -0.4064)
			(end -0.7874 -0.4064)
			(stroke
				(width 0.1524)
				(type default)
			)
			(layer "B.SilkS")
		)
		(fp_line
			(start -0.7874 -0.4064)
			(end -0.7874 0.4064)
			(stroke
				(width 0.1524)
				(type default)
			)
			(layer "B.SilkS")
		)
		(fp_line
			(start 0.7874 0.4064)
			(end 0.7874 -0.4064)
			(stroke
				(width 0.1524)
				(type default)
			)
			(layer "B.SilkS")
		)
		(fp_line
			(start -0.7874 0.4064)
			(end 0.7874 0.4064)
			(stroke
				(width 0.1524)
				(type default)
			)
			(layer "B.SilkS")
		)
		(fp_line
			(start 0.67945 -0.305054)
			(end 0.12065 -0.305054)
			(stroke
				(width 0.1)
				(type default)
			)
			(layer "B.Fab")
		)
		(fp_line
			(start 0.12065 -0.305054)
			(end 0.12065 -0.2794)
			(stroke
				(width 0.1)
				(type default)
			)
			(layer "B.Fab")
		)
		(fp_line
			(start -0.12065 -0.3048)
			(end -0.67945 -0.3048)
			(stroke
				(width 0.1)
				(type default)
			)
			(layer "B.Fab")
		)
		(fp_line
			(start -0.67945 -0.3048)
			(end -0.67945 0.3048)
			(stroke
				(width 0.1)
				(type default)
			)
			(layer "B.Fab")
		)
		(fp_line
			(start 0.12065 -0.2794)
			(end -0.12065 -0.2794)
			(stroke
				(width 0.1)
				(type default)
			)
			(layer "B.Fab")
		)
		(fp_line
			(start -0.12065 -0.2794)
			(end -0.12065 -0.3048)
			(stroke
				(width 0.1)
				(type default)
			)
			(layer "B.Fab")
		)
		(fp_line
			(start 0.12065 0.2794)
			(end 0.12065 0.3048)
			(stroke
				(width 0.1)
				(type default)
			)
			(layer "B.Fab")
		)
		(fp_line
			(start -0.120396 0.2794)
			(end 0.12065 0.2794)
			(stroke
				(width 0.1)
				(type default)
			)
			(layer "B.Fab")
		)
		(fp_line
			(start 0.67945 0.3048)
			(end 0.67945 -0.305054)
			(stroke
				(width 0.1)
				(type default)
			)
			(layer "B.Fab")
		)
		(fp_line
			(start 0.12065 0.3048)
			(end 0.67945 0.3048)
			(stroke
				(width 0.1)
				(type default)
			)
			(layer "B.Fab")
		)
		(fp_line
			(start -0.120396 0.3048)
			(end -0.120396 0.2794)
			(stroke
				(width 0.1)
				(type default)
			)
			(layer "B.Fab")
		)
		(fp_line
			(start -0.67945 0.3048)
			(end -0.120396 0.3048)
			(stroke
				(width 0.1)
				(type default)
			)
			(layer "B.Fab")
		)
		(pad "1" smd circle
			(at 0.40005 0 270)
			(size 0 0)
			(layers "B.Cu" "B.Mask" "B.Paste")
			(net "FM_INT_CPU0_HP_UBM_R_N")
		)
		(pad "2" smd circle
			(at -0.40005 0 270)
			(size 0 0)
			(layers "B.Cu" "B.Mask" "B.Paste")
			(net "FM_INT_CPU0_HP_UBM_N")
		)
	)
	(footprint ""
		(layer "B.Cu")
		(at 159.285686 -408.517344 90)
		(property "Reference" "C6754"
			(at 0 0 90)
			(layer "B.SilkS")
			(hide yes)
			(effects
				(font
					(size 1.27 1.27)
				)
				(justify mirror)
			)
		)
		(property "Value" ""
			(at 0 0 90)
			(layer "B.Fab")
			(effects
				(font
					(size 1.27 1.27)
				)
				(justify mirror)
			)
		)
		(duplicate_pad_numbers_are_jumpers no)
		(fp_line
			(start 0.299974 -0.150114)
			(end -0.299974 -0.150114)
			(stroke
				(width 0.1)
				(type default)
			)
			(layer "B.Fab")
		)
		(fp_line
			(start -0.299974 -0.150114)
			(end -0.299974 0.150114)
			(stroke
				(width 0.1)
				(type default)
			)
			(layer "B.Fab")
		)
		(fp_line
			(start 0.299974 0.150114)
			(end 0.299974 -0.150114)
			(stroke
				(width 0.1)
				(type default)
			)
			(layer "B.Fab")
		)
		(fp_line
			(start -0.299974 0.150114)
			(end 0.299974 0.150114)
			(stroke
				(width 0.1)
				(type default)
			)
			(layer "B.Fab")
		)
		(pad "1" smd rect
			(at 0.2667 0 270)
			(size 0.3048 0.381)
			(layers "B.Cu" "B.Mask" "B.Paste")
			(net "P5E_CPU1_P3_TX_BUF_C_DN<14>")
		)
		(pad "2" smd rect
			(at -0.2667 0 270)
			(size 0.3048 0.381)
			(layers "B.Cu" "B.Mask" "B.Paste")
			(net "P5E_CPU1_P3_TX_BUF_DN<14>")
		)
	)
)
